# BASEBOARD_FAB2 (Tioga Pass) — schematic netlist excerpt (pin names and nets, part order shuffled) for the footprints in the layout excerpt that follows; sources: Cadence DE-HDL packaged netlist, KiCad conversion of Wiwynn_Tioga_Pass_MB.brd

R3T12  RES  10.0K 1% CHIP  pkg 0402  page 153 : A = P3V3_STBY ; B = PU_BIOS_SPI_WP1_N
C1R10  CAP  0.22UF 16V 10% X7R  pkg 0402  page 106 : A = P3E_CPU0_PE3_OCP_TXP<4> ; B = P3E_OCP_CPU0_PE3_C_TXP<4>
C9N20  CAPP  470UF 2.5V 20% ALUM  pkg 3018  page 210 : A = PVSA_CPU1 ; B = GND

(kicad_pcb
	(version 20260206)
	(generator "pcbnew")
	(generator_version "10.0")
	(general
		(thickness 1.6)
		(legacy_teardrops no)
	)
	(paper "A4")
	(title_block
		(title "Wiwynn_Tioga_Pass_MB.brd")
		(comment 1 "Tioga Pass / footprints 4466-4468 of 4770")
	)
	(layers
		(0 "F.Cu" signal "TOP")
		(4 "In1.Cu" signal "L2GND")
		(6 "In2.Cu" signal "L3")
		(8 "In3.Cu" signal "L4GND")
		(10 "In4.Cu" signal "L5")
		(12 "In5.Cu" signal "L6GND")
		(14 "In6.Cu" signal "L7VCC")
		(16 "In7.Cu" signal "L8VCC")
		(18 "In8.Cu" signal "L9GND")
		(20 "In9.Cu" signal "L10")
		(22 "In10.Cu" signal "L11GND")
		(24 "In11.Cu" signal "L12")
		(26 "In12.Cu" signal "L13GND")
		(2 "B.Cu" signal "BOTTOM")
		(9 "F.Adhes" user "F.Adhesive")
		(11 "B.Adhes" user "B.Adhesive")
		(13 "F.Paste" user "Package Geometry/Pastemask Top")
		(15 "B.Paste" user "Package Geometry/Pastemask Bottom")
		(5 "F.SilkS" user "Ref Des/Silkscreen Top")
		(7 "B.SilkS" user "Ref Des/Silkscreen Bottom")
		(1 "F.Mask" user "Board Geometry/Soldermask Top")
		(3 "B.Mask" user "Board Geometry/Soldermask Bottom")
		(17 "Dwgs.User" user "User.Drawings")
		(19 "Cmts.User" user "User.Comments")
		(21 "Eco1.User" user "User.Eco1")
		(23 "Eco2.User" user "User.Eco2")
		(25 "Edge.Cuts" user "Board Geometry/Outline")
		(27 "Margin" user)
		(31 "F.CrtYd" user "Package Geometry/Place Bound Top")
		(29 "B.CrtYd" user "Package Geometry/Place Bound Bottom")
		(35 "F.Fab" user "Ref Des/Assembly Top")
		(33 "B.Fab" user "Ref Des/Assembly Bottom")
	)
	(footprint ""
		(layer "B.Cu")
		(at 386.08 -48.006 90)
		(property "Reference" "R3T12"
			(at 0 0 90)
			(layer "B.SilkS")
			(hide yes)
			(effects
				(font
					(size 1.27 1.27)
				)
				(justify mirror)
			)
		)
		(property "Value" ""
			(at 0 0 90)
			(layer "B.Fab")
			(effects
				(font
					(size 1.27 1.27)
				)
				(justify mirror)
			)
		)
		(duplicate_pad_numbers_are_jumpers no)
		(fp_poly
			(pts
				(xy 0.2794 -0.1016) (xy -0.2794 -0.1016) (xy -0.2794 0.9906) (xy 0.2794 0.9906)
			)
			(stroke
				(width 0)
				(type default)
			)
			(fill no)
			(layer "B.CrtYd")
		)
		(fp_line
			(start 0.2794 -0.1016)
			(end 0.2794 0.9906)
			(stroke
				(width 0.1)
				(type default)
			)
			(layer "B.Fab")
		)
		(fp_line
			(start -0.2794 -0.1016)
			(end 0.2794 -0.1016)
			(stroke
				(width 0.1)
				(type default)
			)
			(layer "B.Fab")
		)
		(fp_line
			(start 0.2794 0.9906)
			(end -0.2794 0.9906)
			(stroke
				(width 0.1)
				(type default)
			)
			(layer "B.Fab")
		)
		(fp_line
			(start -0.2794 0.9906)
			(end -0.2794 -0.1016)
			(stroke
				(width 0.1)
				(type default)
			)
			(layer "B.Fab")
		)
		(pad "1" smd rect
			(at 0 0 270)
			(size 0.508 0.508)
			(layers "B.Cu" "B.Mask" "B.Paste")
			(net "P3V3_STBY")
		)
		(pad "2" smd rect
			(at 0 0.889 270)
			(size 0.508 0.508)
			(layers "B.Cu" "B.Mask" "B.Paste")
			(net "PU_BIOS_SPI_WP1_N")
		)
		(zone
			(layer "B.Cu")
			(hatch none 0.5)
			(connect_pads
				(clearance 0)
			)
			(min_thickness 0.25)
			(keepout
				(tracks allowed)
				(vias not_allowed)
				(pads allowed)
				(copperpour not_allowed)
				(footprints allowed)
			)
			(placement
				(enabled no)
				(sheetname "")
			)
			(fill
				(thermal_gap 0.5)
				(thermal_bridge_width 0.5)
				(island_removal_mode 0)
			)
			(polygon
				(pts
					(xy 386.334 -48.26) (xy 386.334 -47.752) (xy 386.715 -47.752) (xy 386.715 -48.26)
				)
			)
		)
		(zone
			(layer "B.Cu")
			(hatch none 0.5)
			(connect_pads
				(clearance 0)
			)
			(min_thickness 0.25)
			(keepout
				(tracks not_allowed)
				(vias allowed)
				(pads allowed)
				(copperpour not_allowed)
				(footprints allowed)
			)
			(placement
				(enabled no)
				(sheetname "")
			)
			(fill
				(thermal_gap 0.5)
				(thermal_bridge_width 0.5)
				(island_removal_mode 0)
			)
			(polygon
				(pts
					(xy 386.715 -48.26) (xy 386.715 -47.752) (xy 386.334 -47.752) (xy 386.334 -48.26)
				)
			)
		)
	)
	(footprint ""
		(layer "B.Cu")
		(at 449.96735 -52.407058)
		(property "Reference" "C1R10"
			(at 0 0 0)
			(layer "B.SilkS")
			(hide yes)
			(effects
				(font
					(size 1.27 1.27)
				)
				(justify mirror)
			)
		)
		(property "Value" ""
			(at 0 0 0)
			(layer "B.Fab")
			(effects
				(font
					(size 1.27 1.27)
				)
				(justify mirror)
			)
		)
		(duplicate_pad_numbers_are_jumpers no)
		(fp_poly
			(pts
				(xy -0.3048 -0.1016) (xy -0.3048 0.9906) (xy 0.3048 0.9906) (xy 0.3048 -0.1016)
			)
			(stroke
				(width 0)
				(type default)
			)
			(fill no)
			(layer "B.CrtYd")
		)
		(fp_line
			(start -0.3048 -0.1016)
			(end 0.3048 -0.1016)
			(stroke
				(width 0.1)
				(type default)
			)
			(layer "B.Fab")
		)
		(fp_line
			(start -0.3048 0.9906)
			(end -0.3048 -0.1016)
			(stroke
				(width 0.1)
				(type default)
			)
			(layer "B.Fab")
		)
		(fp_line
			(start 0.3048 -0.1016)
			(end 0.3048 0.9906)
			(stroke
				(width 0.1)
				(type default)
			)
			(layer "B.Fab")
		)
		(fp_line
			(start 0.3048 0.9906)
			(end -0.3048 0.9906)
			(stroke
				(width 0.1)
				(type default)
			)
			(layer "B.Fab")
		)
		(pad "1" smd rect
			(at 0 0 180)
			(size 0.508 0.508)
			(layers "B.Cu" "B.Mask" "B.Paste")
			(net "P3E_CPU0_PE3_OCP_TXP<4>")
		)
		(pad "2" smd rect
			(at 0 0.889 180)
			(size 0.508 0.508)
			(layers "B.Cu" "B.Mask" "B.Paste")
			(net "P3E_OCP_CPU0_PE3_C_TXP<4>")
		)
		(zone
			(layer "B.Cu")
			(hatch none 0.5)
			(connect_pads
				(clearance 0)
			)
			(min_thickness 0.25)
			(keepout
				(tracks allowed)
				(vias not_allowed)
				(pads allowed)
				(copperpour not_allowed)
				(footprints allowed)
			)
			(placement
				(enabled no)
				(sheetname "")
			)
			(fill
				(thermal_gap 0.5)
				(thermal_bridge_width 0.5)
				(island_removal_mode 0)
			)
			(polygon
				(pts
					(xy 450.22135 -52.153058) (xy 449.71335 -52.153058) (xy 449.71335 -51.772058) (xy 450.22135 -51.772058)
				)
			)
		)
		(zone
			(layer "B.Cu")
			(hatch none 0.5)
			(connect_pads
				(clearance 0)
			)
			(min_thickness 0.25)
			(keepout
				(tracks not_allowed)
				(vias allowed)
				(pads allowed)
				(copperpour not_allowed)
				(footprints allowed)
			)
			(placement
				(enabled no)
				(sheetname "")
			)
			(fill
				(thermal_gap 0.5)
				(thermal_bridge_width 0.5)
				(island_removal_mode 0)
			)
			(polygon
				(pts
					(xy 450.22135 -51.772058) (xy 449.71335 -51.772058) (xy 449.71335 -52.153058) (xy 450.22135 -52.153058)
				)
			)
		)
	)
	(footprint ""
		(layer "B.Cu")
		(at 45.611796 -95.596202 -90)
		(property "Reference" "C9N20"
			(at 0.626872 -3.791204 0)
			(unlocked yes)
			(layer "B.SilkS")
			(effects
				(font
					(size 0.7874 0.5842)
					(thickness 0.1524)
				)
				(justify mirror)
			)
		)
		(property "Value" ""
			(at 0 0 90)
			(layer "B.Fab")
			(effects
				(font
					(size 1.27 1.27)
				)
				(justify mirror)
			)
		)
		(duplicate_pad_numbers_are_jumpers no)
		(fp_line
			(start -2.286 7.366)
			(end -1.600708 7.366)
			(stroke
				(width 0.1524)
				(type default)
			)
			(layer "B.SilkS")
		)
		(fp_line
			(start -2.286 7.366)
			(end -2.286 1.63195)
			(stroke
				(width 0.1524)
				(type default)
			)
			(layer "B.SilkS")
		)
		(fp_line
			(start 2.286 7.366)
			(end 1.60147 7.366)
			(stroke
				(width 0.1524)
				(type default)
			)
			(layer "B.SilkS")
		)
		(fp_line
			(start 2.286 7.366)
			(end 2.286 1.632712)
			(stroke
				(width 0.1524)
				(type default)
			)
			(layer "B.SilkS")
		)
		(fp_line
			(start -2.504948 1.633728)
			(end -1.6002 1.633728)
			(stroke
				(width 0.1524)
				(type default)
			)
			(layer "B.SilkS")
		)
		(fp_line
			(start 2.563114 1.633728)
			(end 1.6002 1.633728)
			(stroke
				(width 0.1524)
				(type default)
			)
			(layer "B.SilkS")
		)
		(fp_line
			(start -2.504948 -1.616456)
			(end -2.504948 1.633728)
			(stroke
				(width 0.1524)
				(type default)
			)
			(layer "B.SilkS")
		)
		(fp_line
			(start -1.6002 -1.616456)
			(end -2.504948 -1.616456)
			(stroke
				(width 0.1524)
				(type default)
			)
			(layer "B.SilkS")
		)
		(fp_line
			(start 1.6002 -1.616456)
			(end 2.563114 -1.616456)
			(stroke
				(width 0.1524)
				(type default)
			)
			(layer "B.SilkS")
		)
		(fp_line
			(start 2.563114 -1.616456)
			(end 2.563114 1.633728)
			(stroke
				(width 0.1524)
				(type default)
			)
			(layer "B.SilkS")
		)
		(fp_rect
			(start 2.286 7.366)
			(end -2.286 -0.254)
			(stroke
				(width 0)
				(type default)
			)
			(fill no)
			(layer "B.CrtYd")
		)
		(fp_line
			(start -2.286 7.366)
			(end 2.286 7.366)
			(stroke
				(width 0.1)
				(type default)
			)
			(layer "B.Fab")
		)
		(fp_line
			(start 2.286 7.366)
			(end 2.286 -0.254)
			(stroke
				(width 0.1)
				(type default)
			)
			(layer "B.Fab")
		)
		(fp_line
			(start -2.286 -0.254)
			(end -2.286 7.366)
			(stroke
				(width 0.1)
				(type default)
			)
			(layer "B.Fab")
		)
		(fp_line
			(start 2.286 -0.254)
			(end -2.286 -0.254)
			(stroke
				(width 0.1)
				(type default)
			)
			(layer "B.Fab")
		)
		(pad "1" smd rect
			(at 0 0 90)
			(size 2.54 3.048)
			(layers "B.Cu" "B.Mask" "B.Paste")
			(net "PVSA_CPU1")
		)
		(pad "2" smd rect
			(at 0 7.112 90)
			(size 2.54 3.048)
			(layers "B.Cu" "B.Mask" "B.Paste")
			(net "GND")
		)
	)
)
